# T6G (Grand Teton) — schematic netlist excerpt (pin names and nets, part order shuffled) for the footprints in the layout excerpt that follows; sources: Cadence DE-HDL packaged netlist, KiCad conversion of 04192023_DAF0TMB3IC0_F0TG_MB_C_brd_V02_OCP.brd

PR428  Q_RES  5.6 1% CHIP  pkg 0402LF  page 220 : A = SW_PVDDCR_CPU1_P1_BOOT6 ; B = SW_PVDDCR_CPU1_P1_BOOT6_R
R319  Q_RES  1K 1% CHIP  pkg 0402LF  page 250 : A = PCA9548_PCIE3_ADDR1 ; B = GND

(kicad_pcb
	(version 20260206)
	(generator "pcbnew")
	(generator_version "10.0")
	(general
		(thickness 1.6)
		(legacy_teardrops no)
	)
	(paper "A4")
	(title_block
		(title "04192023_DAF0TMB3IC0_F0TG_MB_C_brd_V02_OCP.brd")
		(comment 1 "Grand Teton / footprints 2905-2906 of 8354")
	)
	(layers
		(0 "F.Cu" signal "TOP")
		(4 "In1.Cu" signal "GND")
		(6 "In2.Cu" signal "IN1")
		(8 "In3.Cu" signal "GND1")
		(10 "In4.Cu" signal "IN2")
		(12 "In5.Cu" signal "GND2")
		(14 "In6.Cu" signal "IN3")
		(16 "In7.Cu" signal "GND3")
		(18 "In8.Cu" signal "VCC")
		(20 "In9.Cu" signal "VCC1")
		(22 "In10.Cu" signal "GND4")
		(24 "In11.Cu" signal "IN4")
		(26 "In12.Cu" signal "GND5")
		(28 "In13.Cu" signal "IN5")
		(30 "In14.Cu" signal "GND6")
		(32 "In15.Cu" signal "IN6")
		(34 "In16.Cu" signal "GND7")
		(2 "B.Cu" signal "BOTTOM")
		(9 "F.Adhes" user "F.Adhesive")
		(11 "B.Adhes" user "B.Adhesive")
		(13 "F.Paste" user "Package Geometry/Pastemask Top")
		(15 "B.Paste" user "Package Geometry/Pastemask Bottom")
		(5 "F.SilkS" user "Ref Des/Silkscreen Top")
		(7 "B.SilkS" user "Ref Des/Silkscreen Bottom")
		(1 "F.Mask" user "Board Geometry/Soldermask Top")
		(3 "B.Mask" user "Board Geometry/Soldermask Bottom")
		(17 "Dwgs.User" user "User.Drawings")
		(19 "Cmts.User" user "User.Comments")
		(21 "Eco1.User" user "User.Eco1")
		(23 "Eco2.User" user "User.Eco2")
		(25 "Edge.Cuts" user "Board Geometry/Outline")
		(27 "Margin" user)
		(31 "F.CrtYd" user "Package Geometry/Place Bound Top")
		(29 "B.CrtYd" user "Package Geometry/Place Bound Bottom")
		(35 "F.Fab" user "Ref Des/Assembly Top")
		(33 "B.Fab" user "Ref Des/Assembly Bottom")
	)
	(footprint ""
		(layer "F.Cu")
		(at 104.488488 -344.591132 90)
		(property "Reference" "PR428"
			(at 0 0 90)
			(layer "F.SilkS")
			(hide yes)
			(effects
				(font
					(size 1.27 1.27)
				)
			)
		)
		(property "Value" ""
			(at 0 0 90)
			(layer "F.Fab")
			(effects
				(font
					(size 1.27 1.27)
				)
			)
		)
		(duplicate_pad_numbers_are_jumpers no)
		(fp_line
			(start 0.7874 -0.4064)
			(end 0.7874 0.4064)
			(stroke
				(width 0.1524)
				(type default)
			)
			(layer "F.SilkS")
		)
		(fp_line
			(start -0.7874 -0.4064)
			(end 0.7874 -0.4064)
			(stroke
				(width 0.1524)
				(type default)
			)
			(layer "F.SilkS")
		)
		(fp_line
			(start 0.7874 0.4064)
			(end -0.7874 0.4064)
			(stroke
				(width 0.1524)
				(type default)
			)
			(layer "F.SilkS")
		)
		(fp_line
			(start -0.7874 0.4064)
			(end -0.7874 -0.4064)
			(stroke
				(width 0.1524)
				(type default)
			)
			(layer "F.SilkS")
		)
		(fp_line
			(start -0.12065 -0.305054)
			(end -0.12065 -0.2794)
			(stroke
				(width 0.1)
				(type default)
			)
			(layer "F.Fab")
		)
		(fp_line
			(start -0.67945 -0.305054)
			(end -0.12065 -0.305054)
			(stroke
				(width 0.1)
				(type default)
			)
			(layer "F.Fab")
		)
		(fp_line
			(start 0.67945 -0.3048)
			(end 0.67945 0.3048)
			(stroke
				(width 0.1)
				(type default)
			)
			(layer "F.Fab")
		)
		(fp_line
			(start 0.12065 -0.3048)
			(end 0.67945 -0.3048)
			(stroke
				(width 0.1)
				(type default)
			)
			(layer "F.Fab")
		)
		(fp_line
			(start 0.12065 -0.2794)
			(end 0.12065 -0.3048)
			(stroke
				(width 0.1)
				(type default)
			)
			(layer "F.Fab")
		)
		(fp_line
			(start -0.12065 -0.2794)
			(end 0.12065 -0.2794)
			(stroke
				(width 0.1)
				(type default)
			)
			(layer "F.Fab")
		)
		(fp_line
			(start 0.120396 0.2794)
			(end -0.12065 0.2794)
			(stroke
				(width 0.1)
				(type default)
			)
			(layer "F.Fab")
		)
		(fp_line
			(start -0.12065 0.2794)
			(end -0.12065 0.3048)
			(stroke
				(width 0.1)
				(type default)
			)
			(layer "F.Fab")
		)
		(fp_line
			(start 0.67945 0.3048)
			(end 0.120396 0.3048)
			(stroke
				(width 0.1)
				(type default)
			)
			(layer "F.Fab")
		)
		(fp_line
			(start 0.120396 0.3048)
			(end 0.120396 0.2794)
			(stroke
				(width 0.1)
				(type default)
			)
			(layer "F.Fab")
		)
		(fp_line
			(start -0.12065 0.3048)
			(end -0.67945 0.3048)
			(stroke
				(width 0.1)
				(type default)
			)
			(layer "F.Fab")
		)
		(fp_line
			(start -0.67945 0.3048)
			(end -0.67945 -0.305054)
			(stroke
				(width 0.1)
				(type default)
			)
			(layer "F.Fab")
		)
		(pad "1" smd circle
			(at -0.40005 0 90)
			(size 0 0)
			(layers "F.Cu" "F.Mask" "F.Paste")
			(net "SW_PVDDCR_CPU1_P1_BOOT6")
		)
		(pad "2" smd circle
			(at 0.40005 0 90)
			(size 0 0)
			(layers "F.Cu" "F.Mask" "F.Paste")
			(net "SW_PVDDCR_CPU1_P1_BOOT6_R")
		)
	)
	(footprint ""
		(layer "F.Cu")
		(at 279.513792 -123.035314 180)
		(property "Reference" "R319"
			(at 0 0 180)
			(layer "F.SilkS")
			(hide yes)
			(effects
				(font
					(size 1.27 1.27)
				)
			)
		)
		(property "Value" ""
			(at 0 0 180)
			(layer "F.Fab")
			(effects
				(font
					(size 1.27 1.27)
				)
			)
		)
		(duplicate_pad_numbers_are_jumpers no)
		(fp_line
			(start 0.7874 0.4064)
			(end -0.7874 0.4064)
			(stroke
				(width 0.1524)
				(type default)
			)
			(layer "F.SilkS")
		)
		(fp_line
			(start 0.7874 -0.4064)
			(end 0.7874 0.4064)
			(stroke
				(width 0.1524)
				(type default)
			)
			(layer "F.SilkS")
		)
		(fp_line
			(start -0.7874 0.4064)
			(end -0.7874 -0.4064)
			(stroke
				(width 0.1524)
				(type default)
			)
			(layer "F.SilkS")
		)
		(fp_line
			(start -0.7874 -0.4064)
			(end 0.7874 -0.4064)
			(stroke
				(width 0.1524)
				(type default)
			)
			(layer "F.SilkS")
		)
		(fp_line
			(start 0.67945 0.3048)
			(end 0.120396 0.3048)
			(stroke
				(width 0.1)
				(type default)
			)
			(layer "F.Fab")
		)
		(fp_line
			(start 0.67945 -0.3048)
			(end 0.67945 0.3048)
			(stroke
				(width 0.1)
				(type default)
			)
			(layer "F.Fab")
		)
		(fp_line
			(start 0.12065 -0.2794)
			(end 0.12065 -0.3048)
			(stroke
				(width 0.1)
				(type default)
			)
			(layer "F.Fab")
		)
		(fp_line
			(start 0.12065 -0.3048)
			(end 0.67945 -0.3048)
			(stroke
				(width 0.1)
				(type default)
			)
			(layer "F.Fab")
		)
		(fp_line
			(start 0.120396 0.3048)
			(end 0.120396 0.2794)
			(stroke
				(width 0.1)
				(type default)
			)
			(layer "F.Fab")
		)
		(fp_line
			(start 0.120396 0.2794)
			(end -0.12065 0.2794)
			(stroke
				(width 0.1)
				(type default)
			)
			(layer "F.Fab")
		)
		(fp_line
			(start -0.12065 0.3048)
			(end -0.67945 0.3048)
			(stroke
				(width 0.1)
				(type default)
			)
			(layer "F.Fab")
		)
		(fp_line
			(start -0.12065 0.2794)
			(end -0.12065 0.3048)
			(stroke
				(width 0.1)
				(type default)
			)
			(layer "F.Fab")
		)
		(fp_line
			(start -0.12065 -0.2794)
			(end 0.12065 -0.2794)
			(stroke
				(width 0.1)
				(type default)
			)
			(layer "F.Fab")
		)
		(fp_line
			(start -0.12065 -0.305054)
			(end -0.12065 -0.2794)
			(stroke
				(width 0.1)
				(type default)
			)
			(layer "F.Fab")
		)
		(fp_line
			(start -0.67945 0.3048)
			(end -0.67945 -0.305054)
			(stroke
				(width 0.1)
				(type default)
			)
			(layer "F.Fab")
		)
		(fp_line
			(start -0.67945 -0.305054)
			(end -0.12065 -0.305054)
			(stroke
				(width 0.1)
				(type default)
			)
			(layer "F.Fab")
		)
		(pad "1" smd circle
			(at -0.40005 0 180)
			(size 0 0)
			(layers "F.Cu" "F.Mask" "F.Paste")
			(net "PCA9548_PCIE3_ADDR1")
		)
		(pad "2" smd circle
			(at 0.40005 0 180)
			(size 0 0)
			(layers "F.Cu" "F.Mask" "F.Paste")
			(net "GND")
		)
	)
)
